FILE_TYPE = MACRO_DRAWING;
SET COLOR_WIRE YELLOW;
SET COLOR_PROP MONO;
SET COLOR_DOT WHITE;
SET COLOR_ARC YELLOW;
SET COLOR_BODY GREEN;
SET COLOR_NOTE MONO;
SET PROP_DISPLAY VALUE;
SET PAGE_NUMBER P251;
FORCEADD CAP_A..1
(-1775 5825);
FORCEPROP 1 LAST TOLERANCE 10%
J 0
(-1725 5775);
DISPLAY 0.617021 (-1725 5775);
PAINT SKYBLUE (-1725 5775);
FORCEPROP 1 LAST VOLTAGE 16V
J 0
(-1725 5825);
DISPLAY 0.617021 (-1725 5825);
PAINT SKYBLUE (-1725 5825);
FORCEPROP 1 LASTPIN (-1775 5925) $PN 1
J 0
(-1765 5905);
DISPLAY 0.787234 (-1765 5905);
PAINT ORANGE (-1765 5905);
FORCEPROP 1 LASTPIN (-1775 5725) $PN 2
J 0
(-1765 5705);
DISPLAY 0.787234 (-1765 5705);
PAINT ORANGE (-1765 5705);
FORCEPROP 1 LAST MATERIAL X7R
J 0
(-1725 5725);
DISPLAY 0.617021 (-1725 5725);
PAINT SKYBLUE (-1725 5725);
FORCEPROP 1 LAST LOCATION C10W2
J 0
(-1725 5925);
DISPLAY 0.617021 (-1725 5925);
PAINT AQUA (-1725 5925);
FORCEPROP 1 LAST PACK_TYPE 0402V
J 0
(-1725 5625);
DISPLAY 0.617021 (-1725 5625);
PAINT SKYBLUE (-1725 5625);
FORCEPROP 1 LAST PART_NUMBER A36096-030
J 0
(-1725 5675);
DISPLAY 0.617021 (-1725 5675);
PAINT BLUE (-1725 5675);
FORCEPROP 1 LAST VALUE 0.1UF
J 0
(-1725 5875);
DISPLAY 0.617021 (-1725 5875);
PAINT SKYBLUE (-1725 5875);
FORCEPROP 1 LAST PATH I1
J 0
(-1725 5975);
DISPLAY 0.978723 (-1725 5975);
PAINT WHITE (-1725 5975);
DISPLAY INVISIBLE (-1725 5975);
FORCEPROP 2 LAST CDS_LIB dev_discrete
J 0
(-1775 5825);
PAINT MONO (-1775 5825);
DISPLAY INVISIBLE (-1775 5825);
FORCEPROP 0 LAST BOM_COST SM_THERM
J 0
(-1725 5975);
DISPLAY 1.021277 (-1725 5975);
PAINT ORANGE (-1725 5975);
DISPLAY INVISIBLE (-1725 5975);
FORCEPROP 0 LAST ROOM CPU_FANS
J 0
(-1725 6025);
DISPLAY 1.021277 (-1725 6025);
PAINT ORANGE (-1725 6025);
DISPLAY INVISIBLE (-1725 6025);
FORCEPROP 2 LAST SEC_TYPE 0402V
J 0
(-1725 6025);
DISPLAY 1.021277 (-1725 6025);
PAINT ORANGE (-1725 6025);
DISPLAY INVISIBLE (-1725 6025);
FORCEPROP 2 LAST SEC 1
J 0
(-1725 6025);
DISPLAY 0.680851 (-1725 6025);
PAINT MONO (-1725 6025);
DISPLAY INVISIBLE (-1725 6025);
FORCEPROP 0 LAST CDS_LOCATION C10W2
J 0
(-1725 5975);
PAINT MONO (-1725 5975);
DISPLAY INVISIBLE (-1725 5975);
FORCEPROP 0 LAST CDS_SEC 1
J 0
(-1725 5975);
PAINT MONO (-1725 5975);
DISPLAY INVISIBLE (-1725 5975);
FORCEADD DIODE..4
(-3000 4625);
FORCEPROP 1 LASTPIN (-3000 4725) $PN 1
J 0
(-2985 4695);
DISPLAY 0.702128 (-2985 4695);
PAINT AQUA (-2985 4695);
FORCEPROP 1 LASTPIN (-3000 4525) $PN 2
J 0
(-2985 4525);
DISPLAY 0.702128 (-2985 4525);
PAINT AQUA (-2985 4525);
FORCEPROP 1 LAST LOCATION CR10W2
J 0
(-2900 4730);
DISPLAY 0.617021 (-2900 4730);
PAINT AQUA (-2900 4730);
FORCEPROP 1 LAST VALUE SDMK0340L
J 0
(-2900 4675);
DISPLAY 0.617021 (-2900 4675);
PAINT SKYBLUE (-2900 4675);
FORCEPROP 1 LAST PACK_TYPE SM
J 0
(-2899 4498);
DISPLAY 0.617021 (-2899 4498);
PAINT SKYBLUE (-2899 4498);
FORCEPROP 1 LAST MATERIAL EMPTY
J 0
(-2898 4609);
DISPLAY 0.617021 (-2898 4609);
PAINT RED (-2898 4609);
FORCEPROP 1 LAST PART_NUMBER H71799-001
J 0
(-2900 4550);
DISPLAY 0.617021 (-2900 4550);
PAINT BLUE (-2900 4550);
FORCEPROP 1 LAST PATH I10
J 0
(-2895 4790);
DISPLAY 0.978723 (-2895 4790);
PAINT PINK (-2895 4790);
DISPLAY INVISIBLE (-2895 4790);
FORCEPROP 0 LAST CDS_SEC 1
J 0
(-2900 4775);
PAINT MONO (-2900 4775);
DISPLAY INVISIBLE (-2900 4775);
FORCEPROP 0 LAST CDS_LOCATION CR10W2
J 0
(-2900 4775);
PAINT MONO (-2900 4775);
DISPLAY INVISIBLE (-2900 4775);
FORCEPROP 2 LAST CDS_LIB mstr_discrete
J 0
(-3000 4625);
PAINT MONO (-3000 4625);
DISPLAY INVISIBLE (-3000 4625);
FORCEPROP 0 LAST BOM_COST SM_THERM
J 0
(-2900 4925);
DISPLAY 1.021277 (-2900 4925);
PAINT ORANGE (-2900 4925);
DISPLAY INVISIBLE (-2900 4925);
FORCEPROP 0 LAST ROOM CPU_FANS
J 0
(-2900 4825);
DISPLAY 1.021277 (-2900 4825);
PAINT ORANGE (-2900 4825);
DISPLAY INVISIBLE (-2900 4825);
FORCEPROP 2 LAST SEC_TYPE SM
J 0
(-2875 4850);
DISPLAY 1.021277 (-2875 4850);
PAINT ORANGE (-2875 4850);
DISPLAY INVISIBLE (-2875 4850);
FORCEPROP 2 LAST SEC 1
J 0
(-2875 4850);
DISPLAY 0.680851 (-2875 4850);
PAINT MONO (-2875 4850);
DISPLAY INVISIBLE (-2875 4850);
FORCEADD RES..2
R 2
(-3250 4650);
FORCEPROP 1 LAST PART_NUMBER G21796-072
J 2
(-3290 4525);
DISPLAY 0.617021 (-3290 4525);
PAINT BLUE (-3290 4525);
FORCEPROP 1 LAST PACK_TYPE 0402
J 2
(-3290 4475);
DISPLAY 0.617021 (-3290 4475);
PAINT SKYBLUE (-3290 4475);
FORCEPROP 1 LAST MATERIAL CHIP
J 2
(-3290 4575);
DISPLAY 0.617021 (-3290 4575);
PAINT SKYBLUE (-3290 4575);
FORCEPROP 1 LAST WATTAGE 1/16W
J 2
(-3290 4625);
DISPLAY 0.617021 (-3290 4625);
PAINT SKYBLUE (-3290 4625);
FORCEPROP 1 LASTPIN (-3250 4750) $PN 1
J 2
(-3255 4712);
DISPLAY 0.787234 (-3255 4712);
PAINT ORANGE (-3255 4712);
FORCEPROP 1 LAST LOCATION R10W3
J 2
(-3295 4775);
DISPLAY 0.617021 (-3295 4775);
PAINT AQUA (-3295 4775);
FORCEPROP 1 LASTPIN (-3250 4550) $PN 2
J 2
(-3255 4560);
DISPLAY 0.787234 (-3255 4560);
PAINT ORANGE (-3255 4560);
FORCEPROP 1 LAST TOLERANCE 1%
J 2
(-3295 4675);
DISPLAY 0.617021 (-3295 4675);
PAINT SKYBLUE (-3295 4675);
FORCEPROP 1 LAST VALUE 4.75K
J 2
(-3295 4725);
DISPLAY 0.617021 (-3295 4725);
PAINT SKYBLUE (-3295 4725);
FORCEPROP 1 LAST PATH I11
J 2
(-3300 4825);
DISPLAY 0.978723 (-3300 4825);
PAINT WHITE (-3300 4825);
DISPLAY INVISIBLE (-3300 4825);
FORCEPROP 0 LAST CDS_SEC 1
J 0
(-3275 4825);
PAINT MONO (-3275 4825);
DISPLAY INVISIBLE (-3275 4825);
FORCEPROP 0 LAST CDS_LOCATION R10W3
J 0
(-3275 4825);
PAINT MONO (-3275 4825);
DISPLAY INVISIBLE (-3275 4825);
FORCEPROP 0 LAST ROOM CPU_FANS
J 0
(-3275 4875);
DISPLAY 1.021277 (-3275 4875);
PAINT ORANGE (-3275 4875);
DISPLAY INVISIBLE (-3275 4875);
FORCEPROP 0 LAST BOM_COST SM_THERM
J 0
(-3275 4975);
DISPLAY 1.021277 (-3275 4975);
PAINT ORANGE (-3275 4975);
DISPLAY INVISIBLE (-3275 4975);
FORCEPROP 2 LAST CDS_LIB mstr_discrete
J 0
(-3250 4650);
PAINT MONO (-3250 4650);
DISPLAY INVISIBLE (-3250 4650);
FORCEPROP 2 LAST SEC_TYPE 0402
J 0
(-3300 4875);
DISPLAY 1.021277 (-3300 4875);
PAINT ORANGE (-3300 4875);
DISPLAY INVISIBLE (-3300 4875);
FORCEPROP 2 LAST SEC 1
J 0
(-3300 4875);
DISPLAY 0.680851 (-3300 4875);
PAINT MONO (-3300 4875);
DISPLAY INVISIBLE (-3300 4875);
FORCEADD DIODE..1
(-3200 5250);
FORCEPROP 1 LASTPIN (-3300 5250) $PN 2
J 2
(-3265 5260);
DISPLAY 0.851064 (-3265 5260);
PAINT AQUA (-3265 5260);
FORCEPROP 1 LAST PACK_TYPE SM
J 0
(-3225 5010);
DISPLAY 0.617021 (-3225 5010);
PAINT SKYBLUE (-3225 5010);
FORCEPROP 1 LAST MATERIAL IC
J 0
(-3225 5072);
DISPLAY 0.617021 (-3225 5072);
PAINT SKYBLUE (-3225 5072);
FORCEPROP 1 LAST VALUE SDMK0340L
J 0
(-3225 5125);
DISPLAY 0.617021 (-3225 5125);
PAINT SKYBLUE (-3225 5125);
FORCEPROP 1 LASTPIN (-3100 5250) $PN 1
J 0
(-3135 5260);
DISPLAY 0.851064 (-3135 5260);
PAINT AQUA (-3135 5260);
FORCEPROP 1 LAST LOCATION CR10W1
J 0
(-3227 5406);
DISPLAY 0.617021 (-3227 5406);
PAINT AQUA (-3227 5406);
FORCEPROP 1 LAST PART_NUMBER H71799-001
J 0
(-3225 5350);
DISPLAY 0.617021 (-3225 5350);
PAINT BLUE (-3225 5350);
FORCEPROP 2 LAST SEC_TYPE SM
J 0
(-3200 5525);
DISPLAY 1.021277 (-3200 5525);
PAINT ORANGE (-3200 5525);
DISPLAY INVISIBLE (-3200 5525);
FORCEPROP 2 LAST SEC 1
J 0
(-3200 5525);
DISPLAY 0.680851 (-3200 5525);
PAINT MONO (-3200 5525);
DISPLAY INVISIBLE (-3200 5525);
FORCEPROP 0 LAST ROOM CPU_FANS
J 0
(-3225 5500);
DISPLAY 1.021277 (-3225 5500);
PAINT ORANGE (-3225 5500);
DISPLAY INVISIBLE (-3225 5500);
FORCEPROP 0 LAST BOM_COST SM_THERM
J 0
(-3225 5600);
DISPLAY 1.021277 (-3225 5600);
PAINT ORANGE (-3225 5600);
DISPLAY INVISIBLE (-3225 5600);
FORCEPROP 2 LAST CDS_LIB mstr_discrete
J 0
(-3200 5250);
PAINT MONO (-3200 5250);
DISPLAY INVISIBLE (-3200 5250);
FORCEPROP 0 LAST CDS_LOCATION CR10W1
J 0
(-3225 5450);
PAINT MONO (-3225 5450);
DISPLAY INVISIBLE (-3225 5450);
FORCEPROP 0 LAST CDS_SEC 1
J 0
(-3225 5450);
PAINT MONO (-3225 5450);
DISPLAY INVISIBLE (-3225 5450);
FORCEPROP 1 LAST PATH I12
J 0
(-3220 5460);
DISPLAY 0.978723 (-3220 5460);
PAINT PINK (-3220 5460);
DISPLAY INVISIBLE (-3220 5460);
FORCEADD RES..1
(-4650 5250);
FORCEPROP 1 LAST VALUE 100.0
J 2
(-4675 5150);
DISPLAY 0.617021 (-4675 5150);
PAINT SKYBLUE (-4675 5150);
FORCEPROP 1 LAST WATTAGE 1/16W
J 2
(-4675 5100);
DISPLAY 0.617021 (-4675 5100);
PAINT SKYBLUE (-4675 5100);
FORCEPROP 1 LASTPIN (-4750 5250) $PN 1
J 0
(-4738 5262);
DISPLAY 0.787234 (-4738 5262);
PAINT ORANGE (-4738 5262);
FORCEPROP 1 LAST LOCATION R10W1
J 0
(-4750 5350);
DISPLAY 0.617021 (-4750 5350);
PAINT AQUA (-4750 5350);
FORCEPROP 1 LASTPIN (-4550 5250) $PN 2
J 0
(-4588 5262);
DISPLAY 0.787234 (-4588 5262);
PAINT ORANGE (-4588 5262);
FORCEPROP 1 LAST TOLERANCE 1%
J 0
(-4650 5150);
DISPLAY 0.617021 (-4650 5150);
PAINT SKYBLUE (-4650 5150);
FORCEPROP 1 LAST MATERIAL CHIP
J 0
(-4650 5100);
DISPLAY 0.617021 (-4650 5100);
PAINT SKYBLUE (-4650 5100);
FORCEPROP 1 LAST PART_NUMBER G21796-017
J 0
(-4750 5300);
DISPLAY 0.617021 (-4750 5300);
PAINT BLUE (-4750 5300);
FORCEPROP 1 LAST PACK_TYPE 0402
J 0
(-4550 5150);
DISPLAY 0.617021 (-4550 5150);
PAINT SKYBLUE (-4550 5150);
FORCEPROP 1 LAST PATH I13
J 0
(-4700 5400);
DISPLAY 0.978723 (-4700 5400);
PAINT WHITE (-4700 5400);
DISPLAY INVISIBLE (-4700 5400);
FORCEPROP 0 LAST CDS_SEC 1
J 0
(-4750 5400);
PAINT MONO (-4750 5400);
DISPLAY INVISIBLE (-4750 5400);
FORCEPROP 0 LAST CDS_LOCATION R10W1
J 0
(-4750 5400);
PAINT MONO (-4750 5400);
DISPLAY INVISIBLE (-4750 5400);
FORCEPROP 2 LAST CDS_LIB mstr_discrete
J 0
(-4650 5250);
PAINT MONO (-4650 5250);
DISPLAY INVISIBLE (-4650 5250);
FORCEPROP 0 LAST BOM_COST SM_THERM
J 0
(-4700 5550);
DISPLAY 1.021277 (-4700 5550);
PAINT ORANGE (-4700 5550);
DISPLAY INVISIBLE (-4700 5550);
FORCEPROP 2 LAST NO_XNET_CONNECTION 1
J 0
(-4700 5450);
PAINT MONO (-4700 5450);
DISPLAY INVISIBLE (-4700 5450);
FORCEPROP 0 LAST ROOM CPU_FANS
J 0
(-4700 5450);
DISPLAY 1.021277 (-4700 5450);
PAINT ORANGE (-4700 5450);
DISPLAY INVISIBLE (-4700 5450);
FORCEPROP 2 LAST SEC_TYPE 0402
J 0
(-4700 5450);
DISPLAY 1.021277 (-4700 5450);
PAINT ORANGE (-4700 5450);
DISPLAY INVISIBLE (-4700 5450);
FORCEPROP 2 LAST SEC 1
J 0
(-4700 5450);
DISPLAY 0.680851 (-4700 5450);
PAINT MONO (-4700 5450);
DISPLAY INVISIBLE (-4700 5450);
FORCEADD RES..1
(-4650 4450);
FORCEPROP 1 LAST TOLERANCE 1.0%
J 0
(-4650 4350);
DISPLAY 0.617021 (-4650 4350);
PAINT SKYBLUE (-4650 4350);
FORCEPROP 1 LASTPIN (-4550 4450) $PN 2
J 0
(-4588 4462);
DISPLAY 0.787234 (-4588 4462);
PAINT ORANGE (-4588 4462);
FORCEPROP 1 LAST PACK_TYPE 0402
J 0
(-4400 4300);
DISPLAY 0.617021 (-4400 4300);
PAINT SKYBLUE (-4400 4300);
FORCEPROP 1 LAST MATERIAL CHIP
J 0
(-4650 4300);
DISPLAY 0.617021 (-4650 4300);
PAINT SKYBLUE (-4650 4300);
FORCEPROP 1 LAST LOCATION R10W4
J 0
(-4700 4500);
DISPLAY 0.617021 (-4700 4500);
PAINT AQUA (-4700 4500);
FORCEPROP 1 LAST VALUE 221
J 2
(-4675 4350);
DISPLAY 0.617021 (-4675 4350);
PAINT SKYBLUE (-4675 4350);
FORCEPROP 1 LAST WATTAGE 1/16W
J 2
(-4675 4300);
DISPLAY 0.617021 (-4675 4300);
PAINT SKYBLUE (-4675 4300);
FORCEPROP 1 LAST PART_NUMBER G21796-271
J 0
(-4700 4550);
DISPLAY 0.617021 (-4700 4550);
PAINT BLUE (-4700 4550);
FORCEPROP 1 LASTPIN (-4750 4450) $PN 1
J 0
(-4738 4462);
DISPLAY 0.787234 (-4738 4462);
PAINT ORANGE (-4738 4462);
FORCEPROP 2 LAST CDS_LIB mstr_discrete
J 0
(-4650 4450);
PAINT MONO (-4650 4450);
DISPLAY INVISIBLE (-4650 4450);
FORCEPROP 0 LAST BOM_COST SM_THERM
J 0
(-4700 4750);
DISPLAY 1.021277 (-4700 4750);
PAINT ORANGE (-4700 4750);
DISPLAY INVISIBLE (-4700 4750);
FORCEPROP 0 LAST ROOM CPU_FANS
J 0
(-4700 4650);
DISPLAY 1.021277 (-4700 4650);
PAINT ORANGE (-4700 4650);
DISPLAY INVISIBLE (-4700 4650);
FORCEPROP 2 LAST SEC_TYPE 0402
J 0
(-4700 4650);
DISPLAY 1.021277 (-4700 4650);
PAINT ORANGE (-4700 4650);
DISPLAY INVISIBLE (-4700 4650);
FORCEPROP 2 LAST SEC 1
J 0
(-4700 4650);
DISPLAY 0.680851 (-4700 4650);
PAINT MONO (-4700 4650);
DISPLAY INVISIBLE (-4700 4650);
FORCEPROP 0 LAST CDS_LOCATION R10W4
J 0
(-4700 4600);
PAINT MONO (-4700 4600);
DISPLAY INVISIBLE (-4700 4600);
FORCEPROP 0 LAST CDS_SEC 1
J 0
(-4700 4600);
PAINT MONO (-4700 4600);
DISPLAY INVISIBLE (-4700 4600);
FORCEPROP 1 LAST PATH I14
J 0
(-4700 4600);
DISPLAY 0.978723 (-4700 4600);
PAINT WHITE (-4700 4600);
DISPLAY INVISIBLE (-4700 4600);
FORCEADD RES..2
(-5300 5450);
FORCEPROP 1 LAST LOCATION R10W2
J 0
(-5255 5575);
DISPLAY 0.617021 (-5255 5575);
PAINT AQUA (-5255 5575);
FORCEPROP 1 LAST WATTAGE 1/16W
J 0
(-5260 5425);
DISPLAY 0.617021 (-5260 5425);
PAINT SKYBLUE (-5260 5425);
FORCEPROP 1 LASTPIN (-5300 5550) $PN 1
J 0
(-5295 5512);
DISPLAY 0.787234 (-5295 5512);
PAINT ORANGE (-5295 5512);
FORCEPROP 1 LAST TOLERANCE 1%
J 0
(-5255 5475);
DISPLAY 0.617021 (-5255 5475);
PAINT SKYBLUE (-5255 5475);
FORCEPROP 1 LASTPIN (-5300 5350) $PN 2
J 0
(-5295 5360);
DISPLAY 0.787234 (-5295 5360);
PAINT ORANGE (-5295 5360);
FORCEPROP 1 LAST PACK_TYPE 0402
J 0
(-5260 5275);
DISPLAY 0.617021 (-5260 5275);
PAINT SKYBLUE (-5260 5275);
FORCEPROP 1 LAST MATERIAL CHIP
J 0
(-5260 5375);
DISPLAY 0.617021 (-5260 5375);
PAINT SKYBLUE (-5260 5375);
FORCEPROP 1 LAST VALUE 4.75K
J 0
(-5255 5525);
DISPLAY 0.617021 (-5255 5525);
PAINT SKYBLUE (-5255 5525);
FORCEPROP 1 LAST PART_NUMBER G21796-072
J 0
(-5260 5325);
DISPLAY 0.617021 (-5260 5325);
PAINT BLUE (-5260 5325);
FORCEPROP 1 LAST PATH I15
J 0
(-5250 5625);
DISPLAY 0.978723 (-5250 5625);
PAINT WHITE (-5250 5625);
DISPLAY INVISIBLE (-5250 5625);
FORCEPROP 0 LAST CDS_SEC 1
J 0
(-5250 5625);
PAINT MONO (-5250 5625);
DISPLAY INVISIBLE (-5250 5625);
FORCEPROP 0 LAST CDS_LOCATION R10W2
J 0
(-5250 5625);
PAINT MONO (-5250 5625);
DISPLAY INVISIBLE (-5250 5625);
FORCEPROP 0 LAST ROOM CPU_FANS
J 0
(-5250 5675);
DISPLAY 1.021277 (-5250 5675);
PAINT ORANGE (-5250 5675);
DISPLAY INVISIBLE (-5250 5675);
FORCEPROP 0 LAST BOM_COST SM_THERM
J 0
(-5250 5775);
DISPLAY 1.021277 (-5250 5775);
PAINT ORANGE (-5250 5775);
DISPLAY INVISIBLE (-5250 5775);
FORCEPROP 2 LAST CDS_LIB mstr_discrete
J 0
(-5300 5450);
PAINT MONO (-5300 5450);
DISPLAY INVISIBLE (-5300 5450);
FORCEPROP 2 LAST SEC_TYPE 0402
J 0
(-5250 5675);
DISPLAY 1.021277 (-5250 5675);
PAINT ORANGE (-5250 5675);
DISPLAY INVISIBLE (-5250 5675);
FORCEPROP 2 LAST SEC 1
J 0
(-5250 5675);
DISPLAY 0.680851 (-5250 5675);
PAINT MONO (-5250 5675);
DISPLAY INVISIBLE (-5250 5675);
FORCEADD CAP_A..1
R 2
(-5175 5050);
FORCEPROP 1 LAST MATERIAL X7R
J 2
(-5225 4950);
DISPLAY 0.617021 (-5225 4950);
PAINT SKYBLUE (-5225 4950);
FORCEPROP 1 LAST TOLERANCE 10%
J 2
(-5225 5000);
DISPLAY 0.617021 (-5225 5000);
PAINT SKYBLUE (-5225 5000);
FORCEPROP 1 LASTPIN (-5175 4950) $PN 2
J 2
(-5185 4930);
DISPLAY 0.787234 (-5185 4930);
PAINT ORANGE (-5185 4930);
FORCEPROP 1 LAST PACK_TYPE 0402V
J 2
(-5225 4850);
DISPLAY 0.617021 (-5225 4850);
PAINT SKYBLUE (-5225 4850);
FORCEPROP 1 LASTPIN (-5175 5150) $PN 1
J 2
(-5185 5130);
DISPLAY 0.787234 (-5185 5130);
PAINT ORANGE (-5185 5130);
FORCEPROP 1 LAST VALUE 0.01UF
J 2
(-5225 5100);
DISPLAY 0.617021 (-5225 5100);
PAINT SKYBLUE (-5225 5100);
FORCEPROP 1 LAST VOLTAGE 25V
J 2
(-5225 5050);
DISPLAY 0.617021 (-5225 5050);
PAINT SKYBLUE (-5225 5050);
FORCEPROP 1 LAST PART_NUMBER A36096-045
J 2
(-5225 4900);
DISPLAY 0.617021 (-5225 4900);
PAINT BLUE (-5225 4900);
FORCEPROP 1 LAST LOCATION C10W3
J 2
(-5225 5150);
DISPLAY 0.617021 (-5225 5150);
PAINT AQUA (-5225 5150);
FORCEPROP 1 LAST PATH I16
J 2
(-5225 5200);
DISPLAY 0.978723 (-5225 5200);
PAINT WHITE (-5225 5200);
DISPLAY INVISIBLE (-5225 5200);
FORCEPROP 0 LAST CDS_SEC 1
J 0
(-5225 5200);
PAINT MONO (-5225 5200);
DISPLAY INVISIBLE (-5225 5200);
FORCEPROP 0 LAST CDS_LOCATION C10W3
J 0
(-5225 5200);
PAINT MONO (-5225 5200);
DISPLAY INVISIBLE (-5225 5200);
FORCEPROP 0 LAST BOM_COST SM_THERM
J 0
(-5225 5200);
DISPLAY 1.021277 (-5225 5200);
PAINT ORANGE (-5225 5200);
DISPLAY INVISIBLE (-5225 5200);
FORCEPROP 0 LAST ROOM CPU_FANS
J 0
(-5225 5200);
DISPLAY 1.021277 (-5225 5200);
PAINT ORANGE (-5225 5200);
DISPLAY INVISIBLE (-5225 5200);
FORCEPROP 2 LAST CDS_LIB dev_discrete
J 0
(-5175 5050);
PAINT MONO (-5175 5050);
DISPLAY INVISIBLE (-5175 5050);
FORCEPROP 2 LAST SEC_TYPE 0402V
J 0
(-5225 5250);
DISPLAY 1.021277 (-5225 5250);
PAINT ORANGE (-5225 5250);
DISPLAY INVISIBLE (-5225 5250);
FORCEPROP 2 LAST SEC 1
J 0
(-5225 5250);
DISPLAY 0.680851 (-5225 5250);
PAINT MONO (-5225 5250);
DISPLAY INVISIBLE (-5225 5250);
FORCEADD GND..1
(-5175 4800);
FORCEPROP 3 LASTPIN (-5175 4850) SIG_NAME GND\g
J 0
(-5165 4860);
DISPLAY 0.659574 (-5165 4860);
PAINT MONO (-5165 4860);
DISPLAY INVISIBLE (-5165 4860);
FORCEPROP 1 LAST PATH I17
J 0
(-5100 4800);
DISPLAY 0.872340 (-5100 4800);
PAINT AQUA (-5100 4800);
DISPLAY INVISIBLE (-5100 4800);
FORCEPROP 1 LAST VOLTAGE 0.0V
J 0
(-5220 4757);
DISPLAY 0.340426 (-5220 4757);
PAINT SKYBLUE (-5220 4757);
DISPLAY INVISIBLE (-5220 4757);
FORCEPROP 1 LAST SIZE 1B
J 0
(-5100 4750);
DISPLAY 1.170213 (-5100 4750);
PAINT AQUA (-5100 4750);
DISPLAY INVISIBLE (-5100 4750);
FORCEPROP 2 LAST CDS_LIB mstr_symbols
J 0
(-5175 4800);
PAINT MONO (-5175 4800);
DISPLAY INVISIBLE (-5175 4800);
FORCEPROP 1 LAST BODY_TYPE PLUMBING
J 0
(-5220 4757);
DISPLAY 0.340426 (-5220 4757);
PAINT GREEN (-5220 4757);
DISPLAY INVISIBLE (-5220 4757);
FORCEPROP 1 LAST HDL_POWER GND
J 0
(-5175 4950);
DISPLAY 1.170213 (-5175 4950);
PAINT GREEN (-5175 4950);
DISPLAY INVISIBLE (-5175 4950);
FORCEADD OFFPAGE..2
R 2
(-6000 5250);
FORCEPROP 2 LAST $XR0 147 
J 0
(-6255 5250);
DISPLAY 0.638298 (-6255 5250);
PAINT MONO (-6255 5250);
FORCEPROP 2 LAST PATH I18
J 0
(-6250 5300);
DISPLAY 1.021277 (-6250 5300);
PAINT ORANGE (-6250 5300);
DISPLAY INVISIBLE (-6250 5300);
FORCEPROP 2 LAST CDS_LIB mstr_standard
J 0
(-6000 5250);
PAINT MONO (-6000 5250);
DISPLAY INVISIBLE (-6000 5250);
FORCEPROP 1 LAST OFFPAGE TRUE
J 2
(-6325 5125);
DISPLAY 0.872340 (-6325 5125);
PAINT GREEN (-6325 5125);
DISPLAY INVISIBLE (-6325 5125);
FORCEPROP 1 LAST COMMENT_BODY TRUE
J 2
(-5955 5155);
DISPLAY 0.872340 (-5955 5155);
PAINT GREEN (-5955 5155);
DISPLAY INVISIBLE (-5955 5155);
FORCEADD TTL1G07_A..1
(-6325 4450);
FORCEPROP 1 LAST VALUE 74LVC1G07
J 1
(-6325 4550);
DISPLAY 0.617021 (-6325 4550);
PAINT SKYBLUE (-6325 4550);
FORCEPROP 1 LAST MATERIAL IC
J 0
(-6275 4600);
DISPLAY 0.617021 (-6275 4600);
PAINT SKYBLUE (-6275 4600);
FORCEPROP 1 LAST POWER_GROUP VCC=P3V3_STBY;GND=GND
J 1
(-6700 4360);
DISPLAY 0.617021 (-6700 4360);
PAINT ORANGE (-6700 4360);
FORCEPROP 2 LASTPIN (-6425 4450) $PN 2
J 2
(-6435 4460);
DISPLAY 0.808511 (-6435 4460);
PAINT ORANGE (-6435 4460);
FORCEPROP 1 LAST LOCATION U10W1
J 0
(-6425 4600);
DISPLAY 0.617021 (-6425 4600);
PAINT AQUA (-6425 4600);
FORCEPROP 2 LASTPIN (-6175 4450) $PN 4
J 0
(-6165 4460);
DISPLAY 0.808511 (-6165 4460);
PAINT ORANGE (-6165 4460);
FORCEPROP 1 LAST PART_NUMBER C88419-001
J 0
(-6200 4515);
DISPLAY 0.617021 (-6200 4515);
PAINT BLUE (-6200 4515);
FORCEPROP 1 LAST PACK_TYPE SOP
J 0
(-6375 4700);
DISPLAY 0.978723 (-6375 4700);
PAINT SKYBLUE (-6375 4700);
DISPLAY INVISIBLE (-6375 4700);
FORCEPROP 2 LAST SEC 1
J 0
(-6275 4650);
DISPLAY 0.680851 (-6275 4650);
PAINT MONO (-6275 4650);
DISPLAY INVISIBLE (-6275 4650);
FORCEPROP 2 LAST SEC_TYPE SOP
J 0
(-6275 4650);
DISPLAY 1.021277 (-6275 4650);
PAINT ORANGE (-6275 4650);
DISPLAY INVISIBLE (-6275 4650);
FORCEPROP 0 LAST ROOM CPU_FANS
J 0
(-6375 4750);
DISPLAY 1.021277 (-6375 4750);
PAINT ORANGE (-6375 4750);
DISPLAY INVISIBLE (-6375 4750);
FORCEPROP 0 LAST BOM_COST SM_THERM
J 0
(-6375 4850);
DISPLAY 1.021277 (-6375 4850);
PAINT ORANGE (-6375 4850);
DISPLAY INVISIBLE (-6375 4850);
FORCEPROP 2 LAST CDS_LIB mstr_ttl
J 0
(-6325 4450);
PAINT MONO (-6325 4450);
DISPLAY INVISIBLE (-6325 4450);
FORCEPROP 0 LAST CDS_LOCATION U10W1
J 0
(-6275 4650);
PAINT MONO (-6275 4650);
DISPLAY INVISIBLE (-6275 4650);
FORCEPROP 0 LAST CDS_SEC 1
J 0
(-6275 4650);
PAINT MONO (-6275 4650);
DISPLAY INVISIBLE (-6275 4650);
FORCEPROP 1 LAST PATH I19
J 0
(-6275 4500);
DISPLAY 0.978723 (-6275 4500);
PAINT WHITE (-6275 4500);
DISPLAY INVISIBLE (-6275 4500);
FORCEADD P3V3_STBY..1
(-6650 5075);
FORCEPROP 3 LASTPIN (-6650 5025) SIG_NAME P3V3_STBY\g
J 0
(-6640 5035);
DISPLAY 0.659574 (-6640 5035);
PAINT MONO (-6640 5035);
DISPLAY INVISIBLE (-6640 5035);
FORCEPROP 1 LAST VOLTAGE 3.3V
J 0
(-6695 5032);
DISPLAY 0.340426 (-6695 5032);
PAINT SKYBLUE (-6695 5032);
DISPLAY INVISIBLE (-6695 5032);
FORCEPROP 1 LAST SIZE 1B
J 0
(-6605 5097);
DISPLAY 0.340426 (-6605 5097);
PAINT GREEN (-6605 5097);
DISPLAY INVISIBLE (-6605 5097);
FORCEPROP 2 LAST CDS_LIB mstr_symbols
J 0
(-6650 5075);
PAINT MONO (-6650 5075);
DISPLAY INVISIBLE (-6650 5075);
FORCEPROP 1 LAST PATH I20
J 0
(-6605 5077);
DISPLAY 0.340426 (-6605 5077);
PAINT GREEN (-6605 5077);
DISPLAY INVISIBLE (-6605 5077);
FORCEPROP 1 LAST BODY_TYPE PLUMBING
J 0
(-6695 5032);
DISPLAY 0.340426 (-6695 5032);
PAINT GREEN (-6695 5032);
DISPLAY INVISIBLE (-6695 5032);
FORCEPROP 1 LAST HDL_POWER P3V3_STBY
J 0
(-6950 4950);
DISPLAY 0.872340 (-6950 4950);
PAINT ORANGE (-6950 4950);
DISPLAY INVISIBLE (-6950 4950);
FORCEADD CAP_A..1
(-6650 4900);
FORCEPROP 1 LAST PACK_TYPE 0402V
J 0
(-6600 4700);
DISPLAY 0.617021 (-6600 4700);
PAINT SKYBLUE (-6600 4700);
FORCEPROP 1 LASTPIN (-6650 4800) $PN 2
J 0
(-6640 4780);
DISPLAY 0.787234 (-6640 4780);
PAINT ORANGE (-6640 4780);
FORCEPROP 1 LASTPIN (-6650 5000) $PN 1
J 0
(-6640 4980);
DISPLAY 0.787234 (-6640 4980);
PAINT ORANGE (-6640 4980);
FORCEPROP 1 LAST MATERIAL X7R
J 0
(-6600 4800);
DISPLAY 0.617021 (-6600 4800);
PAINT SKYBLUE (-6600 4800);
FORCEPROP 1 LAST VOLTAGE 16V
J 0
(-6600 4900);
DISPLAY 0.617021 (-6600 4900);
PAINT SKYBLUE (-6600 4900);
FORCEPROP 1 LAST TOLERANCE 10%
J 0
(-6600 4850);
DISPLAY 0.617021 (-6600 4850);
PAINT SKYBLUE (-6600 4850);
FORCEPROP 1 LAST VALUE 0.1UF
J 0
(-6600 4950);
DISPLAY 0.617021 (-6600 4950);
PAINT SKYBLUE (-6600 4950);
FORCEPROP 1 LAST PART_NUMBER A36096-030
J 0
(-6600 4750);
DISPLAY 0.617021 (-6600 4750);
PAINT BLUE (-6600 4750);
FORCEPROP 1 LAST LOCATION C10W4
J 0
(-6600 5000);
DISPLAY 0.617021 (-6600 5000);
PAINT AQUA (-6600 5000);
FORCEPROP 2 LAST SEC 1
J 0
(-6600 5100);
DISPLAY 0.680851 (-6600 5100);
PAINT MONO (-6600 5100);
DISPLAY INVISIBLE (-6600 5100);
FORCEPROP 2 LAST SEC_TYPE 0402V
J 0
(-6600 5100);
DISPLAY 1.021277 (-6600 5100);
PAINT ORANGE (-6600 5100);
DISPLAY INVISIBLE (-6600 5100);
FORCEPROP 0 LAST ROOM CPU_FANS
J 0
(-6600 5100);
DISPLAY 1.021277 (-6600 5100);
PAINT ORANGE (-6600 5100);
DISPLAY INVISIBLE (-6600 5100);
FORCEPROP 0 LAST BOM_COST SM_THERM
J 0
(-6600 5200);
DISPLAY 1.021277 (-6600 5200);
PAINT ORANGE (-6600 5200);
DISPLAY INVISIBLE (-6600 5200);
FORCEPROP 2 LAST CDS_LIB dev_discrete
J 0
(-6650 4900);
PAINT MONO (-6650 4900);
DISPLAY INVISIBLE (-6650 4900);
FORCEPROP 0 LAST CDS_LOCATION C10W4
J 0
(-6600 5050);
PAINT MONO (-6600 5050);
DISPLAY INVISIBLE (-6600 5050);
FORCEPROP 0 LAST CDS_SEC 1
J 0
(-6600 5050);
PAINT MONO (-6600 5050);
DISPLAY INVISIBLE (-6600 5050);
FORCEPROP 1 LAST PATH I21
J 0
(-6600 5050);
DISPLAY 0.978723 (-6600 5050);
PAINT WHITE (-6600 5050);
DISPLAY INVISIBLE (-6600 5050);
FORCEADD GND..1
R 2
(-6650 4700);
FORCEPROP 3 LASTPIN (-6650 4750) SIG_NAME GND\g
J 0
(-6640 4760);
DISPLAY 0.659574 (-6640 4760);
PAINT MONO (-6640 4760);
DISPLAY INVISIBLE (-6640 4760);
FORCEPROP 1 LAST VOLTAGE 0.0V
J 2
(-6605 4657);
DISPLAY 0.340426 (-6605 4657);
PAINT SKYBLUE (-6605 4657);
DISPLAY INVISIBLE (-6605 4657);
FORCEPROP 1 LAST SIZE 1B
J 2
(-6725 4650);
DISPLAY 2.446809 (-6725 4650);
PAINT ORANGE (-6725 4650);
DISPLAY INVISIBLE (-6725 4650);
FORCEPROP 2 LAST ROOM PLD
J 0
(-6850 4780);
DISPLAY 1.595745 (-6850 4780);
PAINT WHITE (-6850 4780);
DISPLAY INVISIBLE (-6850 4780);
FORCEPROP 2 LAST CDS_LIB mstr_symbols
J 0
(-6650 4700);
PAINT MONO (-6650 4700);
DISPLAY INVISIBLE (-6650 4700);
FORCEPROP 1 LAST PATH I22
J 2
(-6725 4700);
DISPLAY 0.872340 (-6725 4700);
PAINT AQUA (-6725 4700);
DISPLAY INVISIBLE (-6725 4700);
FORCEPROP 1 LAST BODY_TYPE PLUMBING
J 2
(-6605 4657);
DISPLAY 0.340426 (-6605 4657);
PAINT GREEN (-6605 4657);
DISPLAY INVISIBLE (-6605 4657);
FORCEPROP 1 LAST HDL_POWER GND
J 2
(-6650 4850);
PAINT GREEN (-6650 4850);
DISPLAY INVISIBLE (-6650 4850);
FORCEADD OFFPAGE..1
(-7275 4450);
FORCEPROP 2 LAST $XR0 147 
J 0
(-7527 4450);
DISPLAY 0.638298 (-7527 4450);
PAINT MONO (-7527 4450);
FORCEPROP 2 LAST CDS_LIB mstr_standard
J 0
(-7275 4450);
PAINT MONO (-7275 4450);
DISPLAY INVISIBLE (-7275 4450);
FORCEPROP 2 LAST PATH I23
J 0
(-7550 4500);
DISPLAY 1.021277 (-7550 4500);
PAINT ORANGE (-7550 4500);
DISPLAY INVISIBLE (-7550 4500);
FORCEPROP 1 LAST OFFPAGE TRUE
J 0
(-6950 4325);
DISPLAY 1.170213 (-6950 4325);
PAINT GREEN (-6950 4325);
DISPLAY INVISIBLE (-6950 4325);
FORCEPROP 1 LAST COMMENT_BODY TRUE
J 0
(-7150 4350);
DISPLAY 1.170213 (-7150 4350);
PAINT PEACH (-7150 4350);
DISPLAY INVISIBLE (-7150 4350);
FORCEADD CONN6_C74770005..1
(-1550 5200);
FORCEPROP 2 LASTPIN (-1650 5300) $PN 2
J 2
(-1660 5310);
DISPLAY 0.617021 (-1660 5310);
PAINT ORANGE (-1660 5310);
FORCEPROP 2 LASTPIN (-1650 5100) $PN 6
J 2
(-1660 5110);
DISPLAY 0.617021 (-1660 5110);
PAINT ORANGE (-1660 5110);
FORCEPROP 2 LASTPIN (-1650 5150) $PN 5
J 2
(-1660 5160);
DISPLAY 0.617021 (-1660 5160);
PAINT ORANGE (-1660 5160);
FORCEPROP 2 LASTPIN (-1650 5250) $PN 3
J 2
(-1660 5260);
DISPLAY 0.617021 (-1660 5260);
PAINT ORANGE (-1660 5260);
FORCEPROP 2 LASTPIN (-1650 5200) $PN 4
J 2
(-1660 5210);
DISPLAY 0.617021 (-1660 5210);
PAINT ORANGE (-1660 5210);
FORCEPROP 1 LAST MATERIAL HDR
J 0
(-1600 5475);
DISPLAY 0.617021 (-1600 5475);
PAINT SKYBLUE (-1600 5475);
FORCEPROP 2 LASTPIN (-1650 5350) $PN 1
J 2
(-1660 5360);
DISPLAY 0.617021 (-1660 5360);
PAINT ORANGE (-1660 5360);
FORCEPROP 1 LAST LOCATION J1B2
J 0
(-1600 5525);
DISPLAY 0.617021 (-1600 5525);
PAINT AQUA (-1600 5525);
FORCEPROP 1 LAST PART_NUMBER C74770-005
J 0
(-1600 4925);
DISPLAY 0.617021 (-1600 4925);
PAINT BLUE (-1600 4925);
FORCEPROP 0 LAST VALUE 0.22UF
J 0
(-1675 5625);
DISPLAY 0.617021 (-1675 5625);
PAINT SKYBLUE (-1675 5625);
DISPLAY INVISIBLE (-1675 5625);
FORCEPROP 0 LAST TOLERANCE 10%
J 0
(-1675 5675);
DISPLAY 0.617021 (-1675 5675);
PAINT SKYBLUE (-1675 5675);
DISPLAY INVISIBLE (-1675 5675);
FORCEPROP 1 LAST PACK_TYPE PIP
J 0
(-1600 5575);
DISPLAY 0.978723 (-1600 5575);
PAINT SKYBLUE (-1600 5575);
DISPLAY INVISIBLE (-1600 5575);
FORCEPROP 0 LAST VOLTAGE 16V
J 0
(-1675 5575);
DISPLAY 0.617021 (-1675 5575);
PAINT SKYBLUE (-1675 5575);
DISPLAY INVISIBLE (-1675 5575);
FORCEPROP 2 LAST SEC_TYPE PIP
J 0
(-1675 5575);
DISPLAY 1.021277 (-1675 5575);
PAINT ORANGE (-1675 5575);
DISPLAY INVISIBLE (-1675 5575);
FORCEPROP 0 LAST BOM_COST SM_THERM
J 0
(-1675 5625);
DISPLAY 1.021277 (-1675 5625);
PAINT ORANGE (-1675 5625);
DISPLAY INVISIBLE (-1675 5625);
FORCEPROP 2 LAST SEC 1
J 0
(-1675 5575);
DISPLAY 0.680851 (-1675 5575);
PAINT MONO (-1675 5575);
DISPLAY INVISIBLE (-1675 5575);
FORCEPROP 0 LAST ROOM CPU_FANS
J 0
(-1675 5575);
DISPLAY 1.021277 (-1675 5575);
PAINT ORANGE (-1675 5575);
DISPLAY INVISIBLE (-1675 5575);
FORCEPROP 2 LAST CDS_LIB mstr_conn
J 0
(-1550 5200);
PAINT ORANGE (-1550 5200);
DISPLAY INVISIBLE (-1550 5200);
FORCEPROP 1 LAST PATH I25
J 0
(-1150 5475);
DISPLAY 0.978723 (-1150 5475);
PAINT BLUE (-1150 5475);
DISPLAY INVISIBLE (-1150 5475);
FORCEPROP 2 LAST CDS_LOCATION J1B2
J 0
(-1675 5525);
DISPLAY 0.617021 (-1675 5525);
PAINT AQUA (-1675 5525);
DISPLAY INVISIBLE (-1675 5525);
FORCEADD DIODE..1
(-3200 3700);
FORCEPROP 1 LAST PART_NUMBER H71799-001
J 0
(-3225 3800);
DISPLAY 0.617021 (-3225 3800);
PAINT BLUE (-3225 3800);
FORCEPROP 1 LAST LOCATION CR10W3
J 0
(-3227 3856);
DISPLAY 0.617021 (-3227 3856);
PAINT AQUA (-3227 3856);
FORCEPROP 1 LASTPIN (-3300 3700) $PN 2
J 2
(-3265 3710);
DISPLAY 0.851064 (-3265 3710);
PAINT AQUA (-3265 3710);
FORCEPROP 1 LAST VALUE SDMK0340L
J 0
(-3225 3575);
DISPLAY 0.617021 (-3225 3575);
PAINT SKYBLUE (-3225 3575);
FORCEPROP 1 LASTPIN (-3100 3700) $PN 1
J 0
(-3135 3710);
DISPLAY 0.851064 (-3135 3710);
PAINT AQUA (-3135 3710);
FORCEPROP 1 LAST PACK_TYPE SM
J 0
(-3225 3460);
DISPLAY 0.617021 (-3225 3460);
PAINT SKYBLUE (-3225 3460);
FORCEPROP 1 LAST MATERIAL IC
J 0
(-3225 3522);
DISPLAY 0.617021 (-3225 3522);
PAINT SKYBLUE (-3225 3522);
FORCEPROP 0 LAST CDS_LOCATION CR10W3
J 0
(-3225 3900);
PAINT MONO (-3225 3900);
DISPLAY INVISIBLE (-3225 3900);
FORCEPROP 0 LAST CDS_SEC 1
J 0
(-3225 3900);
PAINT MONO (-3225 3900);
DISPLAY INVISIBLE (-3225 3900);
FORCEPROP 2 LAST CDS_LIB mstr_discrete
J 0
(-3200 3700);
PAINT MONO (-3200 3700);
DISPLAY INVISIBLE (-3200 3700);
FORCEPROP 0 LAST BOM_COST SM_THERM
J 0
(-3225 4050);
DISPLAY 1.021277 (-3225 4050);
PAINT ORANGE (-3225 4050);
DISPLAY INVISIBLE (-3225 4050);
FORCEPROP 0 LAST ROOM CPU_FANS
J 0
(-3225 3950);
DISPLAY 1.021277 (-3225 3950);
PAINT ORANGE (-3225 3950);
DISPLAY INVISIBLE (-3225 3950);
FORCEPROP 2 LAST SEC 1
J 0
(-3200 3975);
DISPLAY 0.680851 (-3200 3975);
PAINT MONO (-3200 3975);
DISPLAY INVISIBLE (-3200 3975);
FORCEPROP 2 LAST SEC_TYPE SM
J 0
(-3200 3975);
DISPLAY 1.021277 (-3200 3975);
PAINT ORANGE (-3200 3975);
DISPLAY INVISIBLE (-3200 3975);
FORCEPROP 1 LAST PATH I26
J 0
(-3220 3910);
DISPLAY 0.978723 (-3220 3910);
PAINT PINK (-3220 3910);
DISPLAY INVISIBLE (-3220 3910);
FORCEADD RES..1
(-4650 3700);
FORCEPROP 1 LAST MATERIAL CHIP
J 0
(-4650 3550);
DISPLAY 0.617021 (-4650 3550);
PAINT SKYBLUE (-4650 3550);
FORCEPROP 1 LAST TOLERANCE 1%
J 0
(-4650 3600);
DISPLAY 0.617021 (-4650 3600);
PAINT SKYBLUE (-4650 3600);
FORCEPROP 1 LASTPIN (-4550 3700) $PN 2
J 0
(-4588 3712);
DISPLAY 0.787234 (-4588 3712);
PAINT ORANGE (-4588 3712);
FORCEPROP 1 LAST LOCATION R10W6
J 0
(-4750 3800);
DISPLAY 0.617021 (-4750 3800);
PAINT AQUA (-4750 3800);
FORCEPROP 1 LAST PART_NUMBER G21796-017
J 0
(-4750 3750);
DISPLAY 0.617021 (-4750 3750);
PAINT BLUE (-4750 3750);
FORCEPROP 1 LASTPIN (-4750 3700) $PN 1
J 0
(-4738 3712);
DISPLAY 0.787234 (-4738 3712);
PAINT ORANGE (-4738 3712);
FORCEPROP 1 LAST VALUE 100.0
J 2
(-4675 3600);
DISPLAY 0.617021 (-4675 3600);
PAINT SKYBLUE (-4675 3600);
FORCEPROP 1 LAST WATTAGE 1/16W
J 2
(-4675 3550);
DISPLAY 0.617021 (-4675 3550);
PAINT SKYBLUE (-4675 3550);
FORCEPROP 1 LAST PACK_TYPE 0402
J 0
(-4550 3600);
DISPLAY 0.617021 (-4550 3600);
PAINT SKYBLUE (-4550 3600);
FORCEPROP 0 LAST CDS_LOCATION R10W6
J 0
(-4750 3850);
PAINT MONO (-4750 3850);
DISPLAY INVISIBLE (-4750 3850);
FORCEPROP 0 LAST CDS_SEC 1
J 0
(-4750 3850);
PAINT MONO (-4750 3850);
DISPLAY INVISIBLE (-4750 3850);
FORCEPROP 2 LAST CDS_LIB mstr_discrete
J 0
(-4650 3700);
PAINT MONO (-4650 3700);
DISPLAY INVISIBLE (-4650 3700);
FORCEPROP 0 LAST BOM_COST SM_THERM
J 0
(-4700 4000);
DISPLAY 1.021277 (-4700 4000);
PAINT ORANGE (-4700 4000);
DISPLAY INVISIBLE (-4700 4000);
FORCEPROP 2 LAST NO_XNET_CONNECTION 1
J 0
(-4700 3900);
PAINT MONO (-4700 3900);
DISPLAY INVISIBLE (-4700 3900);
FORCEPROP 0 LAST ROOM CPU_FANS
J 0
(-4700 3900);
DISPLAY 1.021277 (-4700 3900);
PAINT ORANGE (-4700 3900);
DISPLAY INVISIBLE (-4700 3900);
FORCEPROP 2 LAST SEC_TYPE 0402
J 0
(-4700 3900);
DISPLAY 1.021277 (-4700 3900);
PAINT ORANGE (-4700 3900);
DISPLAY INVISIBLE (-4700 3900);
FORCEPROP 2 LAST SEC 1
J 0
(-4700 3900);
DISPLAY 0.680851 (-4700 3900);
PAINT MONO (-4700 3900);
DISPLAY INVISIBLE (-4700 3900);
FORCEPROP 1 LAST PATH I27
J 0
(-4700 3850);
DISPLAY 0.978723 (-4700 3850);
PAINT WHITE (-4700 3850);
DISPLAY INVISIBLE (-4700 3850);
FORCEADD OFFPAGE..2
R 2
(-6300 3700);
FORCEPROP 2 LAST $XR0 147 
J 0
(-6585 3700);
DISPLAY 0.638298 (-6585 3700);
PAINT MONO (-6585 3700);
FORCEPROP 2 LAST CDS_LIB mstr_standard
J 0
(-6300 3700);
PAINT MONO (-6300 3700);
DISPLAY INVISIBLE (-6300 3700);
FORCEPROP 2 LAST PATH I28
J 0
(-6550 3750);
DISPLAY 1.021277 (-6550 3750);
PAINT ORANGE (-6550 3750);
DISPLAY INVISIBLE (-6550 3750);
FORCEPROP 1 LAST OFFPAGE TRUE
J 2
(-6625 3575);
DISPLAY 0.872340 (-6625 3575);
PAINT GREEN (-6625 3575);
DISPLAY INVISIBLE (-6625 3575);
FORCEPROP 1 LAST COMMENT_BODY TRUE
J 2
(-6255 3605);
DISPLAY 0.872340 (-6255 3605);
PAINT GREEN (-6255 3605);
DISPLAY INVISIBLE (-6255 3605);
FORCEADD CAP_A..1
R 2
(-5175 3500);
FORCEPROP 1 LAST VALUE 0.01UF
J 2
(-5225 3550);
DISPLAY 0.617021 (-5225 3550);
PAINT SKYBLUE (-5225 3550);
FORCEPROP 1 LASTPIN (-5175 3600) $PN 1
J 2
(-5185 3580);
DISPLAY 0.787234 (-5185 3580);
PAINT ORANGE (-5185 3580);
FORCEPROP 1 LAST PART_NUMBER A36096-045
J 2
(-5225 3350);
DISPLAY 0.617021 (-5225 3350);
PAINT BLUE (-5225 3350);
FORCEPROP 1 LAST MATERIAL X7R
J 2
(-5225 3400);
DISPLAY 0.617021 (-5225 3400);
PAINT SKYBLUE (-5225 3400);
FORCEPROP 1 LASTPIN (-5175 3400) $PN 2
J 2
(-5185 3380);
DISPLAY 0.787234 (-5185 3380);
PAINT ORANGE (-5185 3380);
FORCEPROP 1 LAST VOLTAGE 25V
J 2
(-5225 3500);
DISPLAY 0.617021 (-5225 3500);
PAINT SKYBLUE (-5225 3500);
FORCEPROP 1 LAST LOCATION C10W5
J 2
(-5225 3600);
DISPLAY 0.617021 (-5225 3600);
PAINT AQUA (-5225 3600);
FORCEPROP 1 LAST TOLERANCE 10%
J 2
(-5225 3450);
DISPLAY 0.617021 (-5225 3450);
PAINT SKYBLUE (-5225 3450);
FORCEPROP 1 LAST PACK_TYPE 0402V
J 2
(-5225 3300);
DISPLAY 0.617021 (-5225 3300);
PAINT SKYBLUE (-5225 3300);
FORCEPROP 0 LAST CDS_LOCATION C10W5
J 0
(-5225 3650);
PAINT MONO (-5225 3650);
DISPLAY INVISIBLE (-5225 3650);
FORCEPROP 2 LAST SEC 1
J 0
(-5225 3700);
DISPLAY 0.680851 (-5225 3700);
PAINT MONO (-5225 3700);
DISPLAY INVISIBLE (-5225 3700);
FORCEPROP 2 LAST SEC_TYPE 0402V
J 0
(-5225 3700);
DISPLAY 1.021277 (-5225 3700);
PAINT ORANGE (-5225 3700);
DISPLAY INVISIBLE (-5225 3700);
FORCEPROP 2 LAST CDS_LIB dev_discrete
J 0
(-5175 3500);
PAINT MONO (-5175 3500);
DISPLAY INVISIBLE (-5175 3500);
FORCEPROP 0 LAST ROOM CPU_FANS
J 0
(-5225 3650);
DISPLAY 1.021277 (-5225 3650);
PAINT ORANGE (-5225 3650);
DISPLAY INVISIBLE (-5225 3650);
FORCEPROP 0 LAST BOM_COST SM_THERM
J 0
(-5225 3650);
DISPLAY 1.021277 (-5225 3650);
PAINT ORANGE (-5225 3650);
DISPLAY INVISIBLE (-5225 3650);
FORCEPROP 0 LAST CDS_SEC 1
J 0
(-5225 3650);
PAINT MONO (-5225 3650);
DISPLAY INVISIBLE (-5225 3650);
FORCEPROP 1 LAST PATH I29
J 2
(-5225 3650);
DISPLAY 0.978723 (-5225 3650);
PAINT WHITE (-5225 3650);
DISPLAY INVISIBLE (-5225 3650);
FORCEADD CAP..1
(-2075 5825);
FORCEPROP 1 LAST VALUE 10UF
J 0
(-2025 5875);
DISPLAY 0.617021 (-2025 5875);
PAINT SKYBLUE (-2025 5875);
FORCEPROP 1 LAST VOLTAGE 16V
J 0
(-2025 5825);
DISPLAY 0.617021 (-2025 5825);
PAINT SKYBLUE (-2025 5825);
FORCEPROP 1 LASTPIN (-2075 5925) $PN 1
J 0
(-2065 5905);
DISPLAY 0.787234 (-2065 5905);
PAINT ORANGE (-2065 5905);
FORCEPROP 1 LAST LOCATION C10W1
J 0
(-2025 5925);
DISPLAY 0.617021 (-2025 5925);
PAINT AQUA (-2025 5925);
FORCEPROP 1 LASTPIN (-2075 5725) $PN 2
J 0
(-2065 5705);
DISPLAY 0.787234 (-2065 5705);
PAINT ORANGE (-2065 5705);
FORCEPROP 1 LAST TOLERANCE 10%
J 0
(-2025 5775);
DISPLAY 0.617021 (-2025 5775);
PAINT SKYBLUE (-2025 5775);
FORCEPROP 1 LAST MATERIAL X6S
J 0
(-2025 5725);
DISPLAY 0.617021 (-2025 5725);
PAINT SKYBLUE (-2025 5725);
FORCEPROP 1 LAST PACK_TYPE 0805
J 0
(-2025 5625);
DISPLAY 0.617021 (-2025 5625);
PAINT SKYBLUE (-2025 5625);
FORCEPROP 1 LAST PART_NUMBER C95333-007
J 0
(-2025 5675);
DISPLAY 0.617021 (-2025 5675);
PAINT BLUE (-2025 5675);
FORCEPROP 1 LAST PATH I3
J 0
(-2025 5975);
DISPLAY 0.978723 (-2025 5975);
PAINT WHITE (-2025 5975);
DISPLAY INVISIBLE (-2025 5975);
FORCEPROP 0 LAST CDS_SEC 1
J 0
(-2025 5975);
PAINT MONO (-2025 5975);
DISPLAY INVISIBLE (-2025 5975);
FORCEPROP 0 LAST CDS_LOCATION C10W1
J 0
(-2025 5975);
PAINT MONO (-2025 5975);
DISPLAY INVISIBLE (-2025 5975);
FORCEPROP 2 LAST SEC 1
J 0
(-2025 6025);
DISPLAY 0.680851 (-2025 6025);
PAINT MONO (-2025 6025);
DISPLAY INVISIBLE (-2025 6025);
FORCEPROP 2 LAST SEC_TYPE 0805
J 0
(-2025 6025);
DISPLAY 1.021277 (-2025 6025);
PAINT ORANGE (-2025 6025);
DISPLAY INVISIBLE (-2025 6025);
FORCEPROP 0 LAST BOM_COST SM_THERM
J 0
(-2025 5975);
DISPLAY 1.021277 (-2025 5975);
PAINT ORANGE (-2025 5975);
DISPLAY INVISIBLE (-2025 5975);
FORCEPROP 0 LAST ROOM CPU_FANS
J 0
(-2025 6025);
DISPLAY 1.021277 (-2025 6025);
PAINT ORANGE (-2025 6025);
DISPLAY INVISIBLE (-2025 6025);
FORCEPROP 2 LAST CDS_LIB mstr_discrete
J 0
(-2075 5825);
PAINT MONO (-2075 5825);
DISPLAY INVISIBLE (-2075 5825);
FORCEADD GND..1
(-5175 3250);
FORCEPROP 3 LASTPIN (-5175 3300) SIG_NAME GND\g
J 0
(-5165 3310);
DISPLAY 0.659574 (-5165 3310);
PAINT MONO (-5165 3310);
DISPLAY INVISIBLE (-5165 3310);
FORCEPROP 2 LAST CDS_LIB mstr_symbols
J 0
(-5175 3250);
PAINT MONO (-5175 3250);
DISPLAY INVISIBLE (-5175 3250);
FORCEPROP 1 LAST SIZE 1B
J 0
(-5100 3200);
DISPLAY 1.170213 (-5100 3200);
PAINT AQUA (-5100 3200);
DISPLAY INVISIBLE (-5100 3200);
FORCEPROP 1 LAST VOLTAGE 0.0V
J 0
(-5220 3207);
DISPLAY 0.340426 (-5220 3207);
PAINT SKYBLUE (-5220 3207);
DISPLAY INVISIBLE (-5220 3207);
FORCEPROP 1 LAST PATH I30
J 0
(-5100 3250);
DISPLAY 0.872340 (-5100 3250);
PAINT AQUA (-5100 3250);
DISPLAY INVISIBLE (-5100 3250);
FORCEPROP 1 LAST BODY_TYPE PLUMBING
J 0
(-5220 3207);
DISPLAY 0.340426 (-5220 3207);
PAINT GREEN (-5220 3207);
DISPLAY INVISIBLE (-5220 3207);
FORCEPROP 1 LAST HDL_POWER GND
J 0
(-5175 3400);
DISPLAY 1.170213 (-5175 3400);
PAINT GREEN (-5175 3400);
DISPLAY INVISIBLE (-5175 3400);
FORCEADD RES..2
(-5300 3900);
FORCEPROP 1 LAST PART_NUMBER G21796-072
J 0
(-5260 3775);
DISPLAY 0.617021 (-5260 3775);
PAINT BLUE (-5260 3775);
FORCEPROP 1 LAST PACK_TYPE 0402
J 0
(-5260 3725);
DISPLAY 0.617021 (-5260 3725);
PAINT SKYBLUE (-5260 3725);
FORCEPROP 1 LAST TOLERANCE 1%
J 0
(-5255 3925);
DISPLAY 0.617021 (-5255 3925);
PAINT SKYBLUE (-5255 3925);
FORCEPROP 1 LAST MATERIAL CHIP
J 0
(-5260 3825);
DISPLAY 0.617021 (-5260 3825);
PAINT SKYBLUE (-5260 3825);
FORCEPROP 1 LASTPIN (-5300 3800) $PN 2
J 0
(-5295 3810);
DISPLAY 0.787234 (-5295 3810);
PAINT ORANGE (-5295 3810);
FORCEPROP 1 LAST WATTAGE 1/16W
J 0
(-5260 3875);
DISPLAY 0.617021 (-5260 3875);
PAINT SKYBLUE (-5260 3875);
FORCEPROP 1 LAST VALUE 4.75K
J 0
(-5255 3975);
DISPLAY 0.617021 (-5255 3975);
PAINT SKYBLUE (-5255 3975);
FORCEPROP 1 LASTPIN (-5300 4000) $PN 1
J 0
(-5295 3962);
DISPLAY 0.787234 (-5295 3962);
PAINT ORANGE (-5295 3962);
FORCEPROP 1 LAST LOCATION R10W7
J 0
(-5255 4025);
DISPLAY 0.617021 (-5255 4025);
PAINT AQUA (-5255 4025);
FORCEPROP 0 LAST CDS_LOCATION R10W7
J 0
(-5250 4075);
PAINT MONO (-5250 4075);
DISPLAY INVISIBLE (-5250 4075);
FORCEPROP 2 LAST SEC 1
J 0
(-5250 4125);
DISPLAY 0.680851 (-5250 4125);
PAINT MONO (-5250 4125);
DISPLAY INVISIBLE (-5250 4125);
FORCEPROP 2 LAST SEC_TYPE 0402
J 0
(-5250 4125);
DISPLAY 1.021277 (-5250 4125);
PAINT ORANGE (-5250 4125);
DISPLAY INVISIBLE (-5250 4125);
FORCEPROP 2 LAST CDS_LIB mstr_discrete
J 0
(-5300 3900);
PAINT MONO (-5300 3900);
DISPLAY INVISIBLE (-5300 3900);
FORCEPROP 0 LAST BOM_COST SM_THERM
J 0
(-5250 4225);
DISPLAY 1.021277 (-5250 4225);
PAINT ORANGE (-5250 4225);
DISPLAY INVISIBLE (-5250 4225);
FORCEPROP 0 LAST ROOM CPU_FANS
J 0
(-5250 4125);
DISPLAY 1.021277 (-5250 4125);
PAINT ORANGE (-5250 4125);
DISPLAY INVISIBLE (-5250 4125);
FORCEPROP 0 LAST CDS_SEC 1
J 0
(-5250 4075);
PAINT MONO (-5250 4075);
DISPLAY INVISIBLE (-5250 4075);
FORCEPROP 1 LAST PATH I31
J 0
(-5250 4075);
DISPLAY 0.978723 (-5250 4075);
PAINT WHITE (-5250 4075);
DISPLAY INVISIBLE (-5250 4075);
FORCEADD P3V3_STBY..1
(-5300 4125);
FORCEPROP 3 LASTPIN (-5300 4075) SIG_NAME P3V3_STBY\g
J 0
(-5290 4085);
DISPLAY 0.659574 (-5290 4085);
PAINT MONO (-5290 4085);
DISPLAY INVISIBLE (-5290 4085);
FORCEPROP 2 LAST CDS_LIB mstr_symbols
J 0
(-5300 4125);
PAINT MONO (-5300 4125);
DISPLAY INVISIBLE (-5300 4125);
FORCEPROP 1 LAST SIZE 1B
J 0
(-5255 4147);
DISPLAY 0.340426 (-5255 4147);
PAINT GREEN (-5255 4147);
DISPLAY INVISIBLE (-5255 4147);
FORCEPROP 1 LAST VOLTAGE 3.3V
J 0
(-5345 4082);
DISPLAY 0.340426 (-5345 4082);
PAINT SKYBLUE (-5345 4082);
DISPLAY INVISIBLE (-5345 4082);
FORCEPROP 1 LAST PATH I32
J 0
(-5255 4127);
DISPLAY 0.340426 (-5255 4127);
PAINT GREEN (-5255 4127);
DISPLAY INVISIBLE (-5255 4127);
FORCEPROP 1 LAST BODY_TYPE PLUMBING
J 0
(-5345 4082);
DISPLAY 0.340426 (-5345 4082);
PAINT GREEN (-5345 4082);
DISPLAY INVISIBLE (-5345 4082);
FORCEPROP 1 LAST HDL_POWER P3V3_STBY
J 0
(-5600 4000);
DISPLAY 0.872340 (-5600 4000);
PAINT ORANGE (-5600 4000);
DISPLAY INVISIBLE (-5600 4000);
FORCEADD GND..1
(-2075 5475);
FORCEPROP 3 LASTPIN (-2075 5525) SIG_NAME GND\g
J 0
(-2065 5535);
DISPLAY 0.659574 (-2065 5535);
PAINT MONO (-2065 5535);
DISPLAY INVISIBLE (-2065 5535);
FORCEPROP 1 LAST PATH I4
J 0
(-2000 5475);
DISPLAY 0.872340 (-2000 5475);
PAINT AQUA (-2000 5475);
DISPLAY INVISIBLE (-2000 5475);
FORCEPROP 2 LAST CDS_LIB mstr_symbols
J 0
(-2075 5475);
PAINT MONO (-2075 5475);
DISPLAY INVISIBLE (-2075 5475);
FORCEPROP 1 LAST SIZE 1B
J 0
(-2000 5425);
DISPLAY 1.170213 (-2000 5425);
PAINT AQUA (-2000 5425);
DISPLAY INVISIBLE (-2000 5425);
FORCEPROP 1 LAST VOLTAGE 0.0V
J 0
(-2120 5432);
DISPLAY 0.340426 (-2120 5432);
PAINT SKYBLUE (-2120 5432);
DISPLAY INVISIBLE (-2120 5432);
FORCEPROP 1 LAST BODY_TYPE PLUMBING
J 0
(-2120 5432);
DISPLAY 0.340426 (-2120 5432);
PAINT GREEN (-2120 5432);
DISPLAY INVISIBLE (-2120 5432);
FORCEPROP 1 LAST HDL_POWER GND
J 0
(-2075 5625);
DISPLAY 1.170213 (-2075 5625);
PAINT GREEN (-2075 5625);
DISPLAY INVISIBLE (-2075 5625);
FORCEADD RES..1
(-3025 6025);
FORCEPROP 1 LAST PART_NUMBER G22179-004
J 0
(-3125 6075);
DISPLAY 0.617021 (-3125 6075);
PAINT BLUE (-3125 6075);
FORCEPROP 1 LASTPIN (-3125 6025) $PN 1
J 0
(-3113 6037);
DISPLAY 0.787234 (-3113 6037);
PAINT ORANGE (-3113 6037);
FORCEPROP 1 LASTPIN (-2925 6025) $PN 2
J 0
(-2963 6037);
DISPLAY 0.787234 (-2963 6037);
PAINT ORANGE (-2963 6037);
FORCEPROP 1 LAST TOLERANCE 5%
J 0
(-3025 5925);
DISPLAY 0.617021 (-3025 5925);
PAINT SKYBLUE (-3025 5925);
FORCEPROP 1 LAST MATERIAL CHIP
J 0
(-3025 5875);
DISPLAY 0.617021 (-3025 5875);
PAINT SKYBLUE (-3025 5875);
FORCEPROP 1 LAST LOCATION R10W5
J 0
(-3125 6150);
DISPLAY 0.617021 (-3125 6150);
PAINT AQUA (-3125 6150);
FORCEPROP 1 LAST VALUE 0.0
J 2
(-3050 5925);
DISPLAY 0.617021 (-3050 5925);
PAINT SKYBLUE (-3050 5925);
FORCEPROP 1 LAST WATTAGE 1/8W
J 2
(-3050 5875);
DISPLAY 0.617021 (-3050 5875);
PAINT SKYBLUE (-3050 5875);
FORCEPROP 1 LAST PACK_TYPE 0805
J 0
(-3100 5825);
DISPLAY 0.617021 (-3100 5825);
PAINT SKYBLUE (-3100 5825);
FORCEPROP 1 LAST PATH I5
J 0
(-3075 6175);
DISPLAY 0.978723 (-3075 6175);
PAINT WHITE (-3075 6175);
DISPLAY INVISIBLE (-3075 6175);
FORCEPROP 0 LAST CDS_SEC 1
J 0
(-3125 6200);
PAINT MONO (-3125 6200);
DISPLAY INVISIBLE (-3125 6200);
FORCEPROP 0 LAST CDS_LOCATION R10W5
J 0
(-3125 6200);
PAINT MONO (-3125 6200);
DISPLAY INVISIBLE (-3125 6200);
FORCEPROP 0 LAST ROOM HOT_SWAP
J 0
(-3075 6225);
DISPLAY 1.021277 (-3075 6225);
PAINT ORANGE (-3075 6225);
DISPLAY INVISIBLE (-3075 6225);
FORCEPROP 2 LAST CDS_LIB mstr_discrete
J 0
(-3025 6025);
PAINT MONO (-3025 6025);
DISPLAY INVISIBLE (-3025 6025);
FORCEPROP 2 LAST SEC 1
J 0
(-3075 6225);
DISPLAY 0.680851 (-3075 6225);
PAINT MONO (-3075 6225);
DISPLAY INVISIBLE (-3075 6225);
FORCEPROP 2 LAST SEC_TYPE 0805
J 0
(-3075 6225);
DISPLAY 1.021277 (-3075 6225);
PAINT ORANGE (-3075 6225);
DISPLAY INVISIBLE (-3075 6225);
FORCEADD P12V_FAN..1
(-3325 6125);
FORCEPROP 3 LASTPIN (-3325 6075) SIG_NAME P12V_FAN\g
J 0
(-3315 6085);
DISPLAY 0.659574 (-3315 6085);
PAINT MONO (-3315 6085);
DISPLAY INVISIBLE (-3315 6085);
FORCEPROP 1 LAST PATH I6
J 0
(-3275 6150);
DISPLAY 0.872340 (-3275 6150);
PAINT AQUA (-3275 6150);
DISPLAY INVISIBLE (-3275 6150);
FORCEPROP 1 LAST VOLTAGE 12.0V
J 0
(-3370 6082);
DISPLAY 0.340426 (-3370 6082);
PAINT SKYBLUE (-3370 6082);
DISPLAY INVISIBLE (-3370 6082);
FORCEPROP 2 LAST CDS_LIB mstr_symbols
J 0
(-3325 6125);
PAINT MONO (-3325 6125);
DISPLAY INVISIBLE (-3325 6125);
FORCEPROP 1 LAST BODY_TYPE PLUMBING
J 0
(-3370 6082);
DISPLAY 0.340426 (-3370 6082);
PAINT GREEN (-3370 6082);
DISPLAY INVISIBLE (-3370 6082);
FORCEPROP 1 LAST HDL_POWER P12V_FAN
J 1
(-3325 6175);
DISPLAY 0.872340 (-3325 6175);
PAINT GREEN (-3325 6175);
DISPLAY INVISIBLE (-3325 6175);
FORCEADD P3V3_STBY..1
(-5300 5675);
FORCEPROP 3 LASTPIN (-5300 5625) SIG_NAME P3V3_STBY\g
J 0
(-5290 5635);
DISPLAY 0.659574 (-5290 5635);
PAINT MONO (-5290 5635);
DISPLAY INVISIBLE (-5290 5635);
FORCEPROP 1 LAST PATH I7
J 0
(-5255 5677);
DISPLAY 0.340426 (-5255 5677);
PAINT GREEN (-5255 5677);
DISPLAY INVISIBLE (-5255 5677);
FORCEPROP 1 LAST VOLTAGE 3.3V
J 0
(-5345 5632);
DISPLAY 0.340426 (-5345 5632);
PAINT SKYBLUE (-5345 5632);
DISPLAY INVISIBLE (-5345 5632);
FORCEPROP 1 LAST SIZE 1B
J 0
(-5255 5697);
DISPLAY 0.340426 (-5255 5697);
PAINT GREEN (-5255 5697);
DISPLAY INVISIBLE (-5255 5697);
FORCEPROP 2 LAST CDS_LIB mstr_symbols
J 0
(-5300 5675);
PAINT MONO (-5300 5675);
DISPLAY INVISIBLE (-5300 5675);
FORCEPROP 1 LAST BODY_TYPE PLUMBING
J 0
(-5345 5632);
DISPLAY 0.340426 (-5345 5632);
PAINT GREEN (-5345 5632);
DISPLAY INVISIBLE (-5345 5632);
FORCEPROP 1 LAST HDL_POWER P3V3_STBY
J 0
(-5600 5550);
DISPLAY 0.872340 (-5600 5550);
PAINT ORANGE (-5600 5550);
DISPLAY INVISIBLE (-5600 5550);
FORCEADD GND..1
R 5
(-1850 5350);
FORCEPROP 3 LASTPIN (-1800 5350) SIG_NAME GND\g
J 0
(-1790 5360);
DISPLAY 0.659574 (-1790 5360);
PAINT MONO (-1790 5360);
DISPLAY INVISIBLE (-1790 5360);
FORCEPROP 2 LAST CDS_LIB mstr_symbols
J 0
(-1850 5350);
PAINT MONO (-1850 5350);
DISPLAY INVISIBLE (-1850 5350);
FORCEPROP 1 LAST VOLTAGE 0.0V
R 3
J 0
(-1893 5395);
DISPLAY 0.340426 (-1893 5395);
PAINT SKYBLUE (-1893 5395);
DISPLAY INVISIBLE (-1893 5395);
FORCEPROP 1 LAST SIZE 1B
R 3
J 0
(-1900 5275);
DISPLAY 1.170213 (-1900 5275);
PAINT AQUA (-1900 5275);
DISPLAY INVISIBLE (-1900 5275);
FORCEPROP 1 LAST PATH I8
R 3
J 0
(-1850 5275);
DISPLAY 0.872340 (-1850 5275);
PAINT AQUA (-1850 5275);
DISPLAY INVISIBLE (-1850 5275);
FORCEPROP 1 LAST BODY_TYPE PLUMBING
R 3
J 0
(-1893 5395);
DISPLAY 0.340426 (-1893 5395);
PAINT GREEN (-1893 5395);
DISPLAY INVISIBLE (-1893 5395);
FORCEPROP 1 LAST HDL_POWER GND
R 3
J 0
(-1700 5350);
DISPLAY 1.170213 (-1700 5350);
PAINT GREEN (-1700 5350);
DISPLAY INVISIBLE (-1700 5350);
FORCEADD P5V_STBY..1
(-3000 4925);
FORCEPROP 3 LASTPIN (-3000 4875) SIG_NAME P5V_STBY\g
J 0
(-2990 4885);
DISPLAY 0.659574 (-2990 4885);
PAINT MONO (-2990 4885);
DISPLAY INVISIBLE (-2990 4885);
FORCEPROP 1 LAST PATH I9
J 0
(-2955 4927);
DISPLAY 0.340426 (-2955 4927);
PAINT GREEN (-2955 4927);
DISPLAY INVISIBLE (-2955 4927);
FORCEPROP 2 LAST CDS_LIB mstr_symbols
J 0
(-3000 4925);
PAINT MONO (-3000 4925);
DISPLAY INVISIBLE (-3000 4925);
FORCEPROP 1 LAST SIZE 1B
J 0
(-2955 4947);
DISPLAY 0.340426 (-2955 4947);
PAINT GREEN (-2955 4947);
DISPLAY INVISIBLE (-2955 4947);
FORCEPROP 1 LAST VOLTAGE 5.0V
J 0
(-3045 4882);
DISPLAY 0.340426 (-3045 4882);
PAINT SKYBLUE (-3045 4882);
DISPLAY INVISIBLE (-3045 4882);
FORCEPROP 1 LAST BODY_TYPE PLUMBING
J 0
(-3045 4882);
DISPLAY 0.340426 (-3045 4882);
PAINT GREEN (-3045 4882);
DISPLAY INVISIBLE (-3045 4882);
FORCEPROP 1 LAST HDL_POWER P5V_STBY
J 0
(-3300 4800);
DISPLAY 0.872340 (-3300 4800);
PAINT ORANGE (-3300 4800);
DISPLAY INVISIBLE (-3300 4800);
FORCEADD CAD_NOTE..1
(-6175 4925);
FORCEPROP 0 LAST L2 TO IC
J 0
(-6325 4725);
DISPLAY 0.617021 (-6325 4725);
PAINT WHITE (-6325 4725);
FORCEPROP 0 LAST L1 PLACE CAP CLOSE
J 0
(-6325 4800);
DISPLAY 0.617021 (-6325 4800);
PAINT WHITE (-6325 4800);
FORCEPROP 2 LAST CDS_LIB mstr_symbols
J 0
(-6175 4925);
PAINT MONO (-6175 4925);
DISPLAY INVISIBLE (-6175 4925);
FORCEPROP 1 LAST COMMENT_BODY TRUE
J 0
(-6150 5025);
DISPLAY 1.361702 (-6150 5025);
PAINT WHITE (-6150 5025);
DISPLAY INVISIBLE (-6150 5025);
FORCEADD DNS..2
(-2995 4620);
PAINT RED (-2995 4620);
FORCEPROP 2 LAST CDS_LIB mstr_misc
J 0
(-2995 4620);
PAINT MONO (-2995 4620);
DISPLAY INVISIBLE (-2995 4620);
FORCEPROP 1 LAST COMMENT_BODY TRUE
R 1
J 0
(-2920 4395);
DISPLAY 0.872340 (-2920 4395);
PAINT GREEN (-2920 4395);
DISPLAY INVISIBLE (-2920 4395);
FORCEADD INTEL_CORP_BPAGE..1
(-300 2150);
FORCEPROP 1 LAST CDS_CON_LAST_MODIFIED Fri Jun 16 17:49:31 2017
J 0
(-1725 2475);
PAINT ORANGE (-1725 2475);
DISPLAY INVISIBLE (-1725 2475);
FORCEPROP 2 LAST CUSTOM_TXT_CDS <XR_PAGE_TITLE>
J 0
(-8190 7400);
DISPLAY 0.638298 (-8190 7400);
PAINT PINK (-8190 7400);
DISPLAY INVISIBLE (-8190 7400);
FORCEPROP 2 LAST CUSTOM_TXT_CDS <CURRENT_DESIGN_SHEET> OF <TOTAL_DESIGN_SHEETS>
J 0
(-800 2175);
PAINT ORANGE (-800 2175);
FORCEPROP 2 LAST CUSTOM_TXT_CDS <CON_LAST_MODIFIED>
J 0
(-4300 2250);
PAINT ORANGE (-4300 2250);
FORCEPROP 1 LAST SCH_TITLE PUMP HEADER
J 0
(-8250 2200);
DISPLAY 2.468085 (-8250 2200);
PAINT ORANGE (-8250 2200);
FORCEPROP 2 LAST CDS_LIB mstr_symbols
J 0
(-300 2150);
PAINT MONO (-300 2150);
DISPLAY INVISIBLE (-300 2150);
FORCEPROP 2 LAST PAGE_BORDER TRUE
J 0
(-8190 7400);
DISPLAY 0.638298 (-8190 7400);
PAINT PINK (-8190 7400);
DISPLAY INVISIBLE (-8190 7400);
FORCEPROP 1 LAST COMMENT_BODY TRUE
J 0
(-288 2162);
DISPLAY 0.468085 (-288 2162);
PAINT GREEN (-288 2162);
DISPLAY INVISIBLE (-288 2162);
FORCEPROP 2 LAST CDS_XR_PAGE_TITLE CR-251 : @BASEBOARD_FAB2_LIB.BASEBOARD_FAB2(SCH_1):PAGE251
J 0
(-8190 7400);
DISPLAY 0.638298 (-8190 7400);
PAINT PINK (-8190 7400);
DISPLAY INVISIBLE (-8190 7400);
WIRE 16 -1 (-5175 4950)(-5175 4850);
WIRE 16 -1 (-6650 5025)(-6650 5000);
WIRE 16 -1 (-6650 4800)(-6650 4750);
WIRE 16 -1 (-5175 3400)(-5175 3300);
WIRE 16 -1 (-5300 4075)(-5300 4000);
WIRE 16 -1 (-2075 5625)(-2075 5525);
WIRE 16 -1 (-2075 5625)(-1775 5625);
WIRE 16 -1 (-2075 5625)(-2075 5725);
WIRE 16 -1 (-1775 5725)(-1775 5625);
WIRE 16 -1 (-3325 6075)(-3325 6025);
WIRE 16 -1 (-3325 6025)(-3125 6025);
WIRE 16 -1 (-5300 5625)(-5300 5550);
WIRE 16 -1 (-1800 5350)(-1650 5350);
WIRE 16 -1 (-3000 4875)(-3000 4800);
WIRE 16 -1 (-3250 4800)(-3000 4800);
WIRE 16 -1 (-3000 4800)(-3000 4725);
WIRE 16 -1 (-3250 4750)(-3250 4800);
WIRE 16 -1 (-3100 3700)(-2200 3700);
FORCEPROP 2 LAST SIG_NAME PUMP_TACH1_D
J 0
(-2727 3728);
DISPLAY 0.680851 (-2727 3728);
PAINT ORANGE (-2727 3728);
FORCEPROP 2 LASTPROP $XRERR UNIQUE?
J 0
(-2967 3728);
DISPLAY 0.638298 (-2967 3728);
PAINT MONO (-2967 3728);
DISPLAY INVISIBLE (-2967 3728);
WIRE 16 -1 (-2200 5150)(-2200 3700);
WIRE 16 -1 (-1650 5150)(-2200 5150);
WIRE 3 682 (-6700 4250)(-6700 3150);
WIRE 3 682 (-2050 4250)(-6700 4250);
WIRE 3 682 (-6700 3150)(-2050 3150);
WIRE 3 682 (-2050 3150)(-2050 4250);
WIRE 3 2175 (-7650 2850)(-850 2850);
WIRE 3 2175 (-850 2850)(-850 6225);
WIRE 3 2175 (-7650 2850)(-7650 6225);
WIRE 3 2175 (-7650 6225)(-850 6225);
WIRE 3 682 (-5500 5100)(-6400 5100);
WIRE 3 682 (-5500 5400)(-5500 5100);
WIRE 3 682 (-6400 5100)(-6400 5400);
WIRE 3 682 (-6400 5400)(-5500 5400);
WIRE 16 -1 (-1775 5925)(-1775 6025);
WIRE 16 -1 (-2075 6025)(-2075 5925);
WIRE 16 -1 (-1775 6025)(-2075 6025);
WIRE 16 -1 (-2925 6025)(-2200 6025);
FORCEPROP 2 LAST SIG_NAME P12V_PUMP
J 0
(-2710 6060);
DISPLAY 0.808511 (-2710 6060);
PAINT ORANGE (-2710 6060);
FORCEPROP 2 LASTPROP $XRERR UNIQUE?
J 0
(-2950 6060);
DISPLAY 0.638298 (-2950 6060);
PAINT MONO (-2950 6060);
DISPLAY INVISIBLE (-2950 6060);
WIRE 16 -1 (-2075 6025)(-2200 6025);
WIRE 16 -1 (-2200 5300)(-2200 6025);
WIRE 16 -1 (-2200 5300)(-1650 5300);
WIRE 3 682 (-1750 4850)(-1325 4850);
WIRE 3 682 (-1325 4850)(-1325 5600);
WIRE 3 682 (-1750 5600)(-1750 4850);
WIRE 3 682 (-1750 5600)(-1325 5600);
WIRE 16 -1 (-6250 3700)(-5300 3700);
FORCEPROP 2 LAST SIG_NAME PUMP_TACH1
J 0
(-5852 3728);
DISPLAY 0.680851 (-5852 3728);
PAINT ORANGE (-5852 3728);
WIRE 16 -1 (-5300 3800)(-5300 3700);
WIRE 16 -1 (-5300 3700)(-5175 3700);
WIRE 16 -1 (-5175 3600)(-5175 3700);
WIRE 16 -1 (-5175 3700)(-4750 3700);
WIRE 16 -1 (-4750 4450)(-6175 4450);
FORCEPROP 2 LAST SIG_NAME PUMP_PWM_OUT_BUF
J 0
(-5735 4460);
DISPLAY 0.808511 (-5735 4460);
PAINT ORANGE (-5735 4460);
FORCEPROP 2 LASTPROP $XRERR UNIQUE?
J 0
(-5975 4460);
DISPLAY 0.638298 (-5975 4460);
PAINT MONO (-5975 4460);
DISPLAY INVISIBLE (-5975 4460);
WIRE 16 -1 (-3250 4450)(-4550 4450);
FORCEPROP 2 LAST SIG_NAME PUMP_PWM_OUT_R
J 0
(-4360 4460);
DISPLAY 0.808511 (-4360 4460);
PAINT ORANGE (-4360 4460);
FORCEPROP 2 LASTPROP $XRERR UNIQUE?
J 0
(-4600 4460);
DISPLAY 0.638298 (-4600 4460);
PAINT MONO (-4600 4460);
DISPLAY INVISIBLE (-4600 4460);
WIRE 16 -1 (-3250 4550)(-3250 4450);
WIRE 16 -1 (-3000 4450)(-3250 4450);
WIRE 16 -1 (-3000 4525)(-3000 4450);
WIRE 16 -1 (-2400 5200)(-1650 5200);
WIRE 16 -1 (-2400 4450)(-3000 4450);
WIRE 16 -1 (-2400 4450)(-2400 5200);
WIRE 16 -1 (-3300 3700)(-4550 3700);
FORCEPROP 2 LAST SIG_NAME PUMP_TACH1_R
J 0
(-4027 3728);
DISPLAY 0.680851 (-4027 3728);
PAINT ORANGE (-4027 3728);
FORCEPROP 2 LASTPROP $XRERR UNIQUE?
J 0
(-4267 3728);
DISPLAY 0.638298 (-4267 3728);
PAINT MONO (-4267 3728);
DISPLAY INVISIBLE (-4267 3728);
WIRE 3 682 (-6850 3800)(-6850 3600);
WIRE 3 682 (-6050 3800)(-6850 3800);
WIRE 3 682 (-6850 3600)(-6050 3600);
WIRE 3 682 (-6050 3600)(-6050 3800);
WIRE 16 -1 (-5175 5150)(-5175 5250);
WIRE 16 -1 (-5175 5250)(-4750 5250);
WIRE 16 -1 (-5300 5350)(-5300 5250);
WIRE 16 -1 (-5300 5250)(-5175 5250);
WIRE 16 -1 (-5950 5250)(-5300 5250);
FORCEPROP 2 LAST SIG_NAME PUMP_TACH0
J 0
(-5852 5253);
DISPLAY 0.680851 (-5852 5253);
PAINT ORANGE (-5852 5253);
WIRE 16 -1 (-3300 5250)(-4550 5250);
FORCEPROP 2 LAST SIG_NAME PUMP_TACH_R
J 0
(-4027 5278);
DISPLAY 0.680851 (-4027 5278);
PAINT ORANGE (-4027 5278);
FORCEPROP 2 LASTPROP $XRERR UNIQUE?
J 0
(-4267 5278);
DISPLAY 0.638298 (-4267 5278);
PAINT MONO (-4267 5278);
DISPLAY INVISIBLE (-4267 5278);
WIRE 16 -1 (-3100 5250)(-1650 5250);
FORCEPROP 2 LAST SIG_NAME PUMP_TACH_D
J 0
(-2727 5278);
DISPLAY 0.680851 (-2727 5278);
PAINT ORANGE (-2727 5278);
FORCEPROP 2 LASTPROP $XRERR UNIQUE?
J 0
(-2967 5278);
DISPLAY 0.638298 (-2967 5278);
PAINT MONO (-2967 5278);
DISPLAY INVISIBLE (-2967 5278);
WIRE 16 -1 (-1650 5100)(-2100 5100);
FORCEPROP 2 LAST SIG_NAME TP_PUMP
J 0
(-2085 5110);
DISPLAY 0.638298 (-2085 5110);
PAINT ORANGE (-2085 5110);
FORCEPROP 2 LASTPROP $XRERR UNIQUE?
J 0
(-2340 5100);
DISPLAY 0.638298 (-2340 5100);
PAINT MONO (-2340 5100);
DISPLAY INVISIBLE (-2340 5100);
WIRE 16 -1 (-7225 4450)(-6425 4450);
FORCEPROP 2 LAST SIG_NAME PUMP_PWM_OUT
J 0
(-7060 4460);
DISPLAY 0.808511 (-7060 4460);
PAINT ORANGE (-7060 4460);
DOT 1 (-5300 3700);
DOT 1 (-5175 3700);
DOT 1 (-5300 5250);
DOT 1 (-5175 5250);
DOT 1 (-3250 4450);
DOT 1 (-2200 6025);
DOT 1 (-3000 4450);
DOT 1 (-3000 4800);
DOT 1 (-2075 6025);
DOT 1 (-2075 5625);
FORCENOTE
TP FAB1 CHANGE PN  0216
(-1775 4800) 0;
DISPLAY LEFT (-1775 4800);
DISPLAY 0.808511 (-1775 4800);
PAINT RED (-1775 4800);
FORCENOTE
TP FAB3 CHANGE HEADER TO 6 PIN 0819
(-1775 4750) 0;
DISPLAY LEFT (-1775 4750);
DISPLAY 0.808511 (-1775 4750);
PAINT RED (-1775 4750);
FORCENOTE
TP FAB3 ADD PARTS FOR 6 PIN HEADER 0819
(-6700 3100) 0;
DISPLAY LEFT (-6700 3100);
DISPLAY 0.638298 (-6700 3100);
PAINT RED (-6700 3100);
FORCENOTE
TP FAB3 UNIFY THE NAMING AS PUMP_TACH1 0831
(-6700 3050) 0;
DISPLAY LEFT (-6700 3050);
DISPLAY 0.638298 (-6700 3050);
PAINT RED (-6700 3050);
FORCENOTE
TP FAB3 RECONNECTION 0831
(-6675 3500) 0;
DISPLAY LEFT (-6675 3500);
DISPLAY 0.638298 (-6675 3500);
PAINT RED (-6675 3500);
FORCENOTE
TP FAB3 EXCHANGE LOCATION TO J1B2 0824
(-1775 4650) 0;
DISPLAY LEFT (-1775 4650);
DISPLAY 0.808511 (-1775 4650);
PAINT RED (-1775 4650);
FORCENOTE
TP FAB3 EXCHANGE LOCATION TO J1F2 0824
(-1775 4700) 0;
DISPLAY LEFT (-1775 4700);
DISPLAY 0.808511 (-1775 4700);
PAINT RED (-1775 4700);
FORCENOTE
TP FAB3 RECONNECTION 0823
(-6675 3550) 0;
DISPLAY LEFT (-6675 3550);
DISPLAY 0.638298 (-6675 3550);
PAINT RED (-6675 3550);
FORCENOTE
TP FAB3 RECONNECT ION 0831
(-6400 5425) 0;
DISPLAY LEFT (-6400 5425);
DISPLAY 0.638298 (-6400 5425);
PAINT RED (-6400 5425);
FORCENOTE
TP FAB1 ADD PUMP HEADER CIRCUIT 1225
(-7625 6275) 0;
DISPLAY LEFT (-7625 6275);
DISPLAY 1.021277 (-7625 6275);
PAINT RED (-7625 6275);
QUIT
